G04*
G04 #@! TF.GenerationSoftware,Altium Limited,Altium Designer,23.7.1 (13)*
G04*
G04 Layer_Color=16711935*
%FSLAX25Y25*%
%MOIN*%
G70*
G04*
G04 #@! TF.SameCoordinates,AF00DCEB-AC48-4C7C-91EA-99F42E284231*
G04*
G04*
G04 #@! TF.FilePolarity,Positive*
G04*
G01*
G75*
M02*
